(kicad_pcb
	(version 20260206)
	(generator "pcbnew")
	(generator_version "10.0")
	(general
		(thickness 1.6)
		(legacy_teardrops no)
	)
	(paper "A4")
	(title_block
		(title "panther-plus-userver — 13130-1b_20150205.brd")
		(comment 1 "Honey Badger (Wiwynn) / footprint 894 of 1509 (DIMM1), pads 149-155 of 210")
	)
	(layers
		(0 "F.Cu" signal "TOP")
		(4 "In1.Cu" signal "L2")
		(6 "In2.Cu" signal "L3")
		(8 "In3.Cu" signal "L4")
		(10 "In4.Cu" signal "L5")
		(12 "In5.Cu" signal "L6")
		(14 "In6.Cu" signal "L7")
		(16 "In7.Cu" signal "L8")
		(18 "In8.Cu" signal "L9")
		(20 "In9.Cu" signal "L10")
		(22 "In10.Cu" signal "L11")
		(2 "B.Cu" signal "BOTTOM")
		(9 "F.Adhes" user "F.Adhesive")
		(11 "B.Adhes" user "B.Adhesive")
		(13 "F.Paste" user "Package Geometry/Pastemask Top")
		(15 "B.Paste" user "Package Geometry/Pastemask Bottom")
		(5 "F.SilkS" user "Ref Des/Silkscreen Top")
		(7 "B.SilkS" user "Ref Des/Silkscreen Bottom")
		(1 "F.Mask" user "Board Geometry/Soldermask Top")
		(3 "B.Mask" user "Board Geometry/Soldermask Bottom")
		(17 "Dwgs.User" user "User.Drawings")
		(19 "Cmts.User" user "User.Comments")
		(21 "Eco1.User" user "User.Eco1")
		(23 "Eco2.User" user "User.Eco2")
		(25 "Edge.Cuts" user "Board Geometry/Outline")
		(27 "Margin" user)
		(31 "F.CrtYd" user "Package Geometry/Place Bound Top")
		(29 "B.CrtYd" user "Package Geometry/Place Bound Bottom")
		(35 "F.Fab" user "Ref Des/Assembly Top")
		(33 "B.Fab" user "Ref Des/Assembly Bottom")
	)
	(footprint ""
		(layer "B.Cu")
		(at 158.500064 -66.699892 180)
		(property "Reference" "DIMM1"
			(at 0 0 0)
			(layer "B.SilkS")
			(hide yes)
			(effects
				(font
					(size 1.27 1.27)
				)
				(justify mirror)
			)
		)
		(property "Value" "DDR3-204P-142-COLAY-1-GP-U"
			(at 41.312338 -16.676878 180)
			(unlocked yes)
			(layer "B.Fab")
			(hide yes)
			(effects
				(font
					(size 1.016 1.016)
					(thickness 0.1524)
				)
				(justify mirror)
			)
		)
		(property "Device Type" "AS0A626-J8R6-7H-COLAY-1"
			(at 41.312338 -18.200878 180)
			(unlocked yes)
			(layer "B.Fab")
			(hide yes)
			(effects
				(font
					(size 1.016 1.016)
					(thickness 0.1524)
				)
				(justify mirror)
			)
		)
		(duplicate_pad_numbers_are_jumpers no)
		(pad "147" smd custom
			(at 14.549882 -4.100068)
			(size 0.1143 0.1143)
			(layers "B.Cu" "B.Mask" "B.Paste")
			(net "M_A_DQ35")
			(options
				(clearance outline)
				(anchor circle)
			)
			(primitives
				(gr_poly
					(pts
						(xy 0 -0.9017) (xy -0.03175 -0.89916) (xy -0.0635 -0.889) (xy -0.09144 -0.87376) (xy -0.11684 -0.85344)
						(xy -0.13716 -0.82804) (xy -0.1524 -0.8001) (xy -0.16256 -0.76835) (xy -0.1651 -0.7366) (xy -0.1651 -0.19685)
						(xy -0.17272 -0.18923) (xy -0.17907 -0.18034) (xy -0.18669 -0.17145) (xy -0.19177 -0.16256) (xy -0.19812 -0.15367)
						(xy -0.20828 -0.13335) (xy -0.21971 -0.10287) (xy -0.22225 -0.09271) (xy -0.22479 -0.08128) (xy -0.22606 -0.07112)
						(xy -0.2286 -0.05969) (xy -0.2286 -0.01651) (xy -0.22606 -0.00508) (xy -0.22479 0.00508) (xy -0.22225 0.01651)
						(xy -0.21971 0.02667) (xy -0.20828 0.05715) (xy -0.19812 0.07747) (xy -0.19177 0.08636) (xy -0.18669 0.09525)
						(xy -0.17907 0.10414) (xy -0.17272 0.11303) (xy -0.1651 0.12065) (xy -0.1651 0.7366) (xy -0.16256 0.76835)
						(xy -0.1524 0.8001) (xy -0.13716 0.82804) (xy -0.11684 0.85344) (xy -0.09144 0.87376) (xy -0.0635 0.889)
						(xy -0.03175 0.89916) (xy 0 0.9017) (xy 0.03175 0.89916) (xy 0.0635 0.889) (xy 0.09144 0.87376)
						(xy 0.11684 0.85344) (xy 0.13716 0.82804) (xy 0.1524 0.8001) (xy 0.16256 0.76835) (xy 0.1651 0.7366)
						(xy 0.1651 0.11938) (xy 0.17272 0.11176) (xy 0.19812 0.0762) (xy 0.2032 0.06604) (xy 0.20701 0.05715)
						(xy 0.21209 0.04699) (xy 0.2159 0.03683) (xy 0.21844 0.02667) (xy 0.22225 0.01524) (xy 0.22352 0.00508)
						(xy 0.22606 -0.00508) (xy 0.22733 -0.01651) (xy 0.22733 -0.02667) (xy 0.2286 -0.0381) (xy 0.22733 -0.04953)
						(xy 0.22733 -0.05969) (xy 0.22606 -0.07112) (xy 0.22352 -0.08128) (xy 0.22225 -0.09144) (xy 0.21844 -0.10287)
						(xy 0.2159 -0.11303) (xy 0.21209 -0.12319) (xy 0.20701 -0.13335) (xy 0.2032 -0.14224) (xy 0.19812 -0.1524)
						(xy 0.17272 -0.18796) (xy 0.1651 -0.19558) (xy 0.1651 -0.7366) (xy 0.16256 -0.76835) (xy 0.1524 -0.8001)
						(xy 0.13716 -0.82804) (xy 0.11684 -0.85344) (xy 0.09144 -0.87376) (xy 0.0635 -0.889) (xy 0.03175 -0.89916)
					)
					(width 0)
					(fill yes)
				)
			)
		)
		(pad "148" smd custom
			(at 14.85011 4.100068)
			(size 0.1143 0.1143)
			(layers "B.Cu" "B.Mask" "B.Paste")
			(net "M_A_DQ44")
			(options
				(clearance outline)
				(anchor circle)
			)
			(primitives
				(gr_poly
					(pts
						(xy 0 -0.9017) (xy -0.03175 -0.89916) (xy -0.0635 -0.889) (xy -0.09144 -0.87376) (xy -0.11684 -0.85344)
						(xy -0.13716 -0.82804) (xy -0.1524 -0.8001) (xy -0.16256 -0.76835) (xy -0.1651 -0.7366) (xy -0.1651 -0.11938)
						(xy -0.17272 -0.11176) (xy -0.19812 -0.0762) (xy -0.2032 -0.06604) (xy -0.20701 -0.05715) (xy -0.21209 -0.04699)
						(xy -0.2159 -0.03683) (xy -0.21844 -0.02667) (xy -0.22225 -0.01524) (xy -0.22352 -0.00508) (xy -0.22606 0.00508)
						(xy -0.22733 0.01651) (xy -0.22733 0.02667) (xy -0.2286 0.0381) (xy -0.22733 0.04953) (xy -0.22733 0.05969)
						(xy -0.22606 0.07112) (xy -0.22352 0.08128) (xy -0.22225 0.09144) (xy -0.21844 0.10287) (xy -0.2159 0.11303)
						(xy -0.21209 0.12319) (xy -0.20701 0.13335) (xy -0.2032 0.14224) (xy -0.19812 0.1524) (xy -0.17272 0.18796)
						(xy -0.1651 0.19558) (xy -0.1651 0.7366) (xy -0.16256 0.76835) (xy -0.1524 0.8001) (xy -0.13716 0.82804)
						(xy -0.11684 0.85344) (xy -0.09144 0.87376) (xy -0.0635 0.889) (xy -0.03175 0.89916) (xy 0 0.9017)
						(xy 0.03175 0.89916) (xy 0.0635 0.889) (xy 0.09144 0.87376) (xy 0.11684 0.85344) (xy 0.13716 0.82804)
						(xy 0.1524 0.8001) (xy 0.16256 0.76835) (xy 0.1651 0.7366) (xy 0.1651 0.19685) (xy 0.17272 0.18923)
						(xy 0.17907 0.18034) (xy 0.18669 0.17145) (xy 0.19177 0.16256) (xy 0.19812 0.15367) (xy 0.20828 0.13335)
						(xy 0.21971 0.10287) (xy 0.22225 0.09271) (xy 0.22479 0.08128) (xy 0.22606 0.07112) (xy 0.2286 0.05969)
						(xy 0.2286 0.01651) (xy 0.22606 0.00508) (xy 0.22479 -0.00508) (xy 0.22225 -0.01651) (xy 0.21971 -0.02667)
						(xy 0.20828 -0.05715) (xy 0.19812 -0.07747) (xy 0.19177 -0.08636) (xy 0.18669 -0.09525) (xy 0.17907 -0.10414)
						(xy 0.17272 -0.11303) (xy 0.1651 -0.12065) (xy 0.1651 -0.7366) (xy 0.16256 -0.76835) (xy 0.1524 -0.8001)
						(xy 0.13716 -0.82804) (xy 0.11684 -0.85344) (xy 0.09144 -0.87376) (xy 0.0635 -0.889) (xy 0.03175 -0.89916)
					)
					(width 0)
					(fill yes)
				)
			)
		)
		(pad "149" smd custom
			(at 15.150084 -4.100068)
			(size 0.1143 0.1143)
			(layers "B.Cu" "B.Mask" "B.Paste")
			(net "GND")
			(options
				(clearance outline)
				(anchor circle)
			)
			(primitives
				(gr_poly
					(pts
						(xy 0 -0.9017) (xy -0.03175 -0.89916) (xy -0.0635 -0.889) (xy -0.09144 -0.87376) (xy -0.11684 -0.85344)
						(xy -0.13716 -0.82804) (xy -0.1524 -0.8001) (xy -0.16256 -0.76835) (xy -0.1651 -0.7366) (xy -0.1651 -0.44958)
						(xy -0.17272 -0.44196) (xy -0.19812 -0.4064) (xy -0.2032 -0.39624) (xy -0.20701 -0.38735) (xy -0.21209 -0.37719)
						(xy -0.2159 -0.36703) (xy -0.21844 -0.35687) (xy -0.22225 -0.34544) (xy -0.22352 -0.33528) (xy -0.22606 -0.32512)
						(xy -0.22733 -0.31369) (xy -0.22733 -0.30353) (xy -0.2286 -0.2921) (xy -0.22733 -0.28067) (xy -0.22733 -0.27051)
						(xy -0.22606 -0.25908) (xy -0.22352 -0.24892) (xy -0.22225 -0.23876) (xy -0.21844 -0.22733) (xy -0.2159 -0.21717)
						(xy -0.21209 -0.20701) (xy -0.20701 -0.19685) (xy -0.2032 -0.18796) (xy -0.19812 -0.1778) (xy -0.17272 -0.14224)
						(xy -0.1651 -0.13462) (xy -0.1651 0.7366) (xy -0.16256 0.76835) (xy -0.1524 0.8001) (xy -0.13716 0.82804)
						(xy -0.11684 0.85344) (xy -0.09144 0.87376) (xy -0.0635 0.889) (xy -0.03175 0.89916) (xy 0 0.9017)
						(xy 0.03175 0.89916) (xy 0.0635 0.889) (xy 0.09144 0.87376) (xy 0.11684 0.85344) (xy 0.13716 0.82804)
						(xy 0.1524 0.8001) (xy 0.16256 0.76835) (xy 0.1651 0.7366) (xy 0.1651 -0.13462) (xy 0.17272 -0.14224)
						(xy 0.19812 -0.1778) (xy 0.2032 -0.18796) (xy 0.20701 -0.19685) (xy 0.21209 -0.20701) (xy 0.2159 -0.21717)
						(xy 0.21844 -0.22733) (xy 0.22225 -0.23876) (xy 0.22352 -0.24892) (xy 0.22606 -0.25908) (xy 0.22733 -0.27051)
						(xy 0.22733 -0.28067) (xy 0.2286 -0.2921) (xy 0.22733 -0.30353) (xy 0.22733 -0.31369) (xy 0.22606 -0.32512)
						(xy 0.22352 -0.33528) (xy 0.22225 -0.34544) (xy 0.21844 -0.35687) (xy 0.2159 -0.36703) (xy 0.21209 -0.37719)
						(xy 0.20701 -0.38735) (xy 0.2032 -0.39624) (xy 0.19812 -0.4064) (xy 0.17272 -0.44196) (xy 0.1651 -0.44958)
						(xy 0.1651 -0.7366) (xy 0.16256 -0.76835) (xy 0.1524 -0.8001) (xy 0.13716 -0.82804) (xy 0.11684 -0.85344)
						(xy 0.09144 -0.87376) (xy 0.0635 -0.889) (xy 0.03175 -0.89916)
					)
					(width 0)
					(fill yes)
				)
			)
		)
		(pad "150" smd custom
			(at 15.450058 4.100068)
			(size 0.1143 0.1143)
			(layers "B.Cu" "B.Mask" "B.Paste")
			(net "M_A_DQ45")
			(options
				(clearance outline)
				(anchor circle)
			)
			(primitives
				(gr_poly
					(pts
						(xy 0 -0.9017) (xy -0.03175 -0.89916) (xy -0.0635 -0.889) (xy -0.09144 -0.87376) (xy -0.11684 -0.85344)
						(xy -0.13716 -0.82804) (xy -0.1524 -0.8001) (xy -0.16256 -0.76835) (xy -0.1651 -0.7366) (xy -0.1651 0.13462)
						(xy -0.17272 0.14224) (xy -0.19812 0.1778) (xy -0.2032 0.18796) (xy -0.20701 0.19685) (xy -0.21209 0.20701)
						(xy -0.2159 0.21717) (xy -0.21844 0.22733) (xy -0.22225 0.23876) (xy -0.22352 0.24892) (xy -0.22606 0.25908)
						(xy -0.22733 0.27051) (xy -0.22733 0.28067) (xy -0.2286 0.2921) (xy -0.22733 0.30353) (xy -0.22733 0.31369)
						(xy -0.22606 0.32512) (xy -0.22352 0.33528) (xy -0.22225 0.34544) (xy -0.21844 0.35687) (xy -0.2159 0.36703)
						(xy -0.21209 0.37719) (xy -0.20701 0.38735) (xy -0.2032 0.39624) (xy -0.19812 0.4064) (xy -0.17272 0.44196)
						(xy -0.1651 0.44958) (xy -0.1651 0.7366) (xy -0.16256 0.76835) (xy -0.1524 0.8001) (xy -0.13716 0.82804)
						(xy -0.11684 0.85344) (xy -0.09144 0.87376) (xy -0.0635 0.889) (xy -0.03175 0.89916) (xy 0 0.9017)
						(xy 0.03175 0.89916) (xy 0.0635 0.889) (xy 0.09144 0.87376) (xy 0.11684 0.85344) (xy 0.13716 0.82804)
						(xy 0.1524 0.8001) (xy 0.16256 0.76835) (xy 0.1651 0.7366) (xy 0.1651 0.44958) (xy 0.17272 0.44196)
						(xy 0.19812 0.4064) (xy 0.2032 0.39624) (xy 0.20701 0.38735) (xy 0.21209 0.37719) (xy 0.2159 0.36703)
						(xy 0.21844 0.35687) (xy 0.22225 0.34544) (xy 0.22352 0.33528) (xy 0.22606 0.32512) (xy 0.22733 0.31369)
						(xy 0.22733 0.30353) (xy 0.2286 0.2921) (xy 0.22733 0.28067) (xy 0.22733 0.27051) (xy 0.22606 0.25908)
						(xy 0.22352 0.24892) (xy 0.22225 0.23876) (xy 0.21844 0.22733) (xy 0.2159 0.21717) (xy 0.21209 0.20701)
						(xy 0.20701 0.19685) (xy 0.2032 0.18796) (xy 0.19812 0.1778) (xy 0.17272 0.14224) (xy 0.1651 0.13462)
						(xy 0.1651 -0.7366) (xy 0.16256 -0.76835) (xy 0.1524 -0.8001) (xy 0.13716 -0.82804) (xy 0.11684 -0.85344)
						(xy 0.09144 -0.87376) (xy 0.0635 -0.889) (xy 0.03175 -0.89916)
					)
					(width 0)
					(fill yes)
				)
			)
		)
		(pad "151" smd custom
			(at 15.750032 -4.100068)
			(size 0.1143 0.1143)
			(layers "B.Cu" "B.Mask" "B.Paste")
			(net "M_A_DQ40")
			(options
				(clearance outline)
				(anchor circle)
			)
			(primitives
				(gr_poly
					(pts
						(xy 0 -0.9017) (xy -0.03175 -0.89916) (xy -0.0635 -0.889) (xy -0.09144 -0.87376) (xy -0.11684 -0.85344)
						(xy -0.13716 -0.82804) (xy -0.1524 -0.8001) (xy -0.16256 -0.76835) (xy -0.1651 -0.7366) (xy -0.1651 -0.19685)
						(xy -0.17272 -0.18923) (xy -0.17907 -0.18034) (xy -0.18669 -0.17145) (xy -0.19177 -0.16256) (xy -0.19812 -0.15367)
						(xy -0.20828 -0.13335) (xy -0.21971 -0.10287) (xy -0.22225 -0.09271) (xy -0.22479 -0.08128) (xy -0.22606 -0.07112)
						(xy -0.2286 -0.05969) (xy -0.2286 -0.01651) (xy -0.22606 -0.00508) (xy -0.22479 0.00508) (xy -0.22225 0.01651)
						(xy -0.21971 0.02667) (xy -0.20828 0.05715) (xy -0.19812 0.07747) (xy -0.19177 0.08636) (xy -0.18669 0.09525)
						(xy -0.17907 0.10414) (xy -0.17272 0.11303) (xy -0.1651 0.12065) (xy -0.1651 0.7366) (xy -0.16256 0.76835)
						(xy -0.1524 0.8001) (xy -0.13716 0.82804) (xy -0.11684 0.85344) (xy -0.09144 0.87376) (xy -0.0635 0.889)
						(xy -0.03175 0.89916) (xy 0 0.9017) (xy 0.03175 0.89916) (xy 0.0635 0.889) (xy 0.09144 0.87376)
						(xy 0.11684 0.85344) (xy 0.13716 0.82804) (xy 0.1524 0.8001) (xy 0.16256 0.76835) (xy 0.1651 0.7366)
						(xy 0.1651 0.11938) (xy 0.17272 0.11176) (xy 0.19812 0.0762) (xy 0.2032 0.06604) (xy 0.20701 0.05715)
						(xy 0.21209 0.04699) (xy 0.2159 0.03683) (xy 0.21844 0.02667) (xy 0.22225 0.01524) (xy 0.22352 0.00508)
						(xy 0.22606 -0.00508) (xy 0.22733 -0.01651) (xy 0.22733 -0.02667) (xy 0.2286 -0.0381) (xy 0.22733 -0.04953)
						(xy 0.22733 -0.05969) (xy 0.22606 -0.07112) (xy 0.22352 -0.08128) (xy 0.22225 -0.09144) (xy 0.21844 -0.10287)
						(xy 0.2159 -0.11303) (xy 0.21209 -0.12319) (xy 0.20701 -0.13335) (xy 0.2032 -0.14224) (xy 0.19812 -0.1524)
						(xy 0.17272 -0.18796) (xy 0.1651 -0.19558) (xy 0.1651 -0.7366) (xy 0.16256 -0.76835) (xy 0.1524 -0.8001)
						(xy 0.13716 -0.82804) (xy 0.11684 -0.85344) (xy 0.09144 -0.87376) (xy 0.0635 -0.889) (xy 0.03175 -0.89916)
					)
					(width 0)
					(fill yes)
				)
			)
		)
		(pad "152" smd custom
			(at 16.050006 4.100068)
			(size 0.1143 0.1143)
			(layers "B.Cu" "B.Mask" "B.Paste")
			(net "GND")
			(options
				(clearance outline)
				(anchor circle)
			)
			(primitives
				(gr_poly
					(pts
						(xy 0 -0.9017) (xy -0.03175 -0.89916) (xy -0.0635 -0.889) (xy -0.09144 -0.87376) (xy -0.11684 -0.85344)
						(xy -0.13716 -0.82804) (xy -0.1524 -0.8001) (xy -0.16256 -0.76835) (xy -0.1651 -0.7366) (xy -0.1651 -0.11938)
						(xy -0.17272 -0.11176) (xy -0.19812 -0.0762) (xy -0.2032 -0.06604) (xy -0.20701 -0.05715) (xy -0.21209 -0.04699)
						(xy -0.2159 -0.03683) (xy -0.21844 -0.02667) (xy -0.22225 -0.01524) (xy -0.22352 -0.00508) (xy -0.22606 0.00508)
						(xy -0.22733 0.01651) (xy -0.22733 0.02667) (xy -0.2286 0.0381) (xy -0.22733 0.04953) (xy -0.22733 0.05969)
						(xy -0.22606 0.07112) (xy -0.22352 0.08128) (xy -0.22225 0.09144) (xy -0.21844 0.10287) (xy -0.2159 0.11303)
						(xy -0.21209 0.12319) (xy -0.20701 0.13335) (xy -0.2032 0.14224) (xy -0.19812 0.1524) (xy -0.17272 0.18796)
						(xy -0.1651 0.19558) (xy -0.1651 0.7366) (xy -0.16256 0.76835) (xy -0.1524 0.8001) (xy -0.13716 0.82804)
						(xy -0.11684 0.85344) (xy -0.09144 0.87376) (xy -0.0635 0.889) (xy -0.03175 0.89916) (xy 0 0.9017)
						(xy 0.03175 0.89916) (xy 0.0635 0.889) (xy 0.09144 0.87376) (xy 0.11684 0.85344) (xy 0.13716 0.82804)
						(xy 0.1524 0.8001) (xy 0.16256 0.76835) (xy 0.1651 0.7366) (xy 0.1651 0.19685) (xy 0.17272 0.18923)
						(xy 0.17907 0.18034) (xy 0.18669 0.17145) (xy 0.19177 0.16256) (xy 0.19812 0.15367) (xy 0.20828 0.13335)
						(xy 0.21971 0.10287) (xy 0.22225 0.09271) (xy 0.22479 0.08128) (xy 0.22606 0.07112) (xy 0.2286 0.05969)
						(xy 0.2286 0.01651) (xy 0.22606 0.00508) (xy 0.22479 -0.00508) (xy 0.22225 -0.01651) (xy 0.21971 -0.02667)
						(xy 0.20828 -0.05715) (xy 0.19812 -0.07747) (xy 0.19177 -0.08636) (xy 0.18669 -0.09525) (xy 0.17907 -0.10414)
						(xy 0.17272 -0.11303) (xy 0.1651 -0.12065) (xy 0.1651 -0.7366) (xy 0.16256 -0.76835) (xy 0.1524 -0.8001)
						(xy 0.13716 -0.82804) (xy 0.11684 -0.85344) (xy 0.09144 -0.87376) (xy 0.0635 -0.889) (xy 0.03175 -0.89916)
					)
					(width 0)
					(fill yes)
				)
			)
		)
		(pad "153" smd custom
			(at 16.34998 -4.100068)
			(size 0.1143 0.1143)
			(layers "B.Cu" "B.Mask" "B.Paste")
			(net "M_A_DQ41")
			(options
				(clearance outline)
				(anchor circle)
			)
			(primitives
				(gr_poly
					(pts
						(xy 0 -0.9017) (xy -0.03175 -0.89916) (xy -0.0635 -0.889) (xy -0.09144 -0.87376) (xy -0.11684 -0.85344)
						(xy -0.13716 -0.82804) (xy -0.1524 -0.8001) (xy -0.16256 -0.76835) (xy -0.1651 -0.7366) (xy -0.1651 -0.44958)
						(xy -0.17272 -0.44196) (xy -0.19812 -0.4064) (xy -0.2032 -0.39624) (xy -0.20701 -0.38735) (xy -0.21209 -0.37719)
						(xy -0.2159 -0.36703) (xy -0.21844 -0.35687) (xy -0.22225 -0.34544) (xy -0.22352 -0.33528) (xy -0.22606 -0.32512)
						(xy -0.22733 -0.31369) (xy -0.22733 -0.30353) (xy -0.2286 -0.2921) (xy -0.22733 -0.28067) (xy -0.22733 -0.27051)
						(xy -0.22606 -0.25908) (xy -0.22352 -0.24892) (xy -0.22225 -0.23876) (xy -0.21844 -0.22733) (xy -0.2159 -0.21717)
						(xy -0.21209 -0.20701) (xy -0.20701 -0.19685) (xy -0.2032 -0.18796) (xy -0.19812 -0.1778) (xy -0.17272 -0.14224)
						(xy -0.1651 -0.13462) (xy -0.1651 0.7366) (xy -0.16256 0.76835) (xy -0.1524 0.8001) (xy -0.13716 0.82804)
						(xy -0.11684 0.85344) (xy -0.09144 0.87376) (xy -0.0635 0.889) (xy -0.03175 0.89916) (xy 0 0.9017)
						(xy 0.03175 0.89916) (xy 0.0635 0.889) (xy 0.09144 0.87376) (xy 0.11684 0.85344) (xy 0.13716 0.82804)
						(xy 0.1524 0.8001) (xy 0.16256 0.76835) (xy 0.1651 0.7366) (xy 0.1651 -0.13462) (xy 0.17272 -0.14224)
						(xy 0.19812 -0.1778) (xy 0.2032 -0.18796) (xy 0.20701 -0.19685) (xy 0.21209 -0.20701) (xy 0.2159 -0.21717)
						(xy 0.21844 -0.22733) (xy 0.22225 -0.23876) (xy 0.22352 -0.24892) (xy 0.22606 -0.25908) (xy 0.22733 -0.27051)
						(xy 0.22733 -0.28067) (xy 0.2286 -0.2921) (xy 0.22733 -0.30353) (xy 0.22733 -0.31369) (xy 0.22606 -0.32512)
						(xy 0.22352 -0.33528) (xy 0.22225 -0.34544) (xy 0.21844 -0.35687) (xy 0.2159 -0.36703) (xy 0.21209 -0.37719)
						(xy 0.20701 -0.38735) (xy 0.2032 -0.39624) (xy 0.19812 -0.4064) (xy 0.17272 -0.44196) (xy 0.1651 -0.44958)
						(xy 0.1651 -0.7366) (xy 0.16256 -0.76835) (xy 0.1524 -0.8001) (xy 0.13716 -0.82804) (xy 0.11684 -0.85344)
						(xy 0.09144 -0.87376) (xy 0.0635 -0.889) (xy 0.03175 -0.89916)
					)
					(width 0)
					(fill yes)
				)
			)
		)
	)
)
